(kicad_pcb
	(version 20260206)
	(generator "pcbnew")
	(generator_version "10.0")
	(general
		(thickness 1.6)
		(legacy_teardrops no)
	)
	(paper "A4")
	(title_block
		(title "01162023_DA0F0TEBIF0_F0T_Expander_BD_F_brd_V02_OCP.brd")
		(comment 1 "Grand Teton / footprints 3712-3718 of 9728")
	)
	(layers
		(0 "F.Cu" signal "TOP")
		(4 "In1.Cu" signal "GND")
		(6 "In2.Cu" signal "VCC")
		(8 "In3.Cu" signal "VCC1")
		(10 "In4.Cu" signal "GND1")
		(12 "In5.Cu" signal "IN1")
		(14 "In6.Cu" signal "GND2")
		(16 "In7.Cu" signal "IN2")
		(18 "In8.Cu" signal "GND3")
		(20 "In9.Cu" signal "IN3")
		(22 "In10.Cu" signal "GND4")
		(24 "In11.Cu" signal "IN4")
		(26 "In12.Cu" signal "GND5")
		(28 "In13.Cu" signal "IN5")
		(30 "In14.Cu" signal "GND6")
		(32 "In15.Cu" signal "IN6")
		(34 "In16.Cu" signal "GND7")
		(2 "B.Cu" signal "BOTTOM")
		(9 "F.Adhes" user "F.Adhesive")
		(11 "B.Adhes" user "B.Adhesive")
		(13 "F.Paste" user "Package Geometry/Pastemask Top")
		(15 "B.Paste" user "Package Geometry/Pastemask Bottom")
		(5 "F.SilkS" user "Ref Des/Silkscreen Top")
		(7 "B.SilkS" user "Ref Des/Silkscreen Bottom")
		(1 "F.Mask" user "Board Geometry/Soldermask Top")
		(3 "B.Mask" user "Board Geometry/Soldermask Bottom")
		(17 "Dwgs.User" user "User.Drawings")
		(19 "Cmts.User" user "User.Comments")
		(21 "Eco1.User" user "User.Eco1")
		(23 "Eco2.User" user "User.Eco2")
		(25 "Edge.Cuts" user "Board Geometry/Outline")
		(27 "Margin" user)
		(31 "F.CrtYd" user "Package Geometry/Place Bound Top")
		(29 "B.CrtYd" user "Package Geometry/Place Bound Bottom")
		(35 "F.Fab" user "Ref Des/Assembly Top")
		(33 "B.Fab" user "Ref Des/Assembly Bottom")
	)
	(footprint ""
		(layer "F.Cu")
		(at 194.367912 -51.019456)
		(property "Reference" "PC387"
			(at 0 0 0)
			(layer "F.SilkS")
			(hide yes)
			(effects
				(font
					(size 1.27 1.27)
				)
			)
		)
		(property "Value" ""
			(at 0 0 0)
			(layer "F.Fab")
			(effects
				(font
					(size 1.27 1.27)
				)
			)
		)
		(duplicate_pad_numbers_are_jumpers no)
		(fp_line
			(start -0.7874 -0.4064)
			(end 0.7874 -0.4064)
			(stroke
				(width 0.1524)
				(type default)
			)
			(layer "F.SilkS")
		)
		(fp_line
			(start -0.7874 0.4064)
			(end -0.7874 -0.4064)
			(stroke
				(width 0.1524)
				(type default)
			)
			(layer "F.SilkS")
		)
		(fp_line
			(start 0.7874 -0.4064)
			(end 0.7874 0.4064)
			(stroke
				(width 0.1524)
				(type default)
			)
			(layer "F.SilkS")
		)
		(fp_line
			(start 0.7874 0.4064)
			(end -0.7874 0.4064)
			(stroke
				(width 0.1524)
				(type default)
			)
			(layer "F.SilkS")
		)
		(fp_line
			(start -0.67945 -0.305054)
			(end -0.12065 -0.305054)
			(stroke
				(width 0.1)
				(type default)
			)
			(layer "F.Fab")
		)
		(fp_line
			(start -0.67945 0.3048)
			(end -0.67945 -0.305054)
			(stroke
				(width 0.1)
				(type default)
			)
			(layer "F.Fab")
		)
		(fp_line
			(start -0.12065 -0.305054)
			(end -0.12065 -0.2794)
			(stroke
				(width 0.1)
				(type default)
			)
			(layer "F.Fab")
		)
		(fp_line
			(start -0.12065 -0.2794)
			(end 0.12065 -0.2794)
			(stroke
				(width 0.1)
				(type default)
			)
			(layer "F.Fab")
		)
		(fp_line
			(start -0.12065 0.2794)
			(end -0.12065 0.3048)
			(stroke
				(width 0.1)
				(type default)
			)
			(layer "F.Fab")
		)
		(fp_line
			(start -0.12065 0.3048)
			(end -0.67945 0.3048)
			(stroke
				(width 0.1)
				(type default)
			)
			(layer "F.Fab")
		)
		(fp_line
			(start 0.120396 0.2794)
			(end -0.12065 0.2794)
			(stroke
				(width 0.1)
				(type default)
			)
			(layer "F.Fab")
		)
		(fp_line
			(start 0.120396 0.3048)
			(end 0.120396 0.2794)
			(stroke
				(width 0.1)
				(type default)
			)
			(layer "F.Fab")
		)
		(fp_line
			(start 0.12065 -0.3048)
			(end 0.67945 -0.3048)
			(stroke
				(width 0.1)
				(type default)
			)
			(layer "F.Fab")
		)
		(fp_line
			(start 0.12065 -0.2794)
			(end 0.12065 -0.3048)
			(stroke
				(width 0.1)
				(type default)
			)
			(layer "F.Fab")
		)
		(fp_line
			(start 0.67945 -0.3048)
			(end 0.67945 0.3048)
			(stroke
				(width 0.1)
				(type default)
			)
			(layer "F.Fab")
		)
		(fp_line
			(start 0.67945 0.3048)
			(end 0.120396 0.3048)
			(stroke
				(width 0.1)
				(type default)
			)
			(layer "F.Fab")
		)
		(pad "1" smd circle
			(at -0.40005 0)
			(size 0 0)
			(layers "F.Cu" "F.Mask" "F.Paste")
			(net "P12V_SSD6_SS")
		)
		(pad "2" smd circle
			(at 0.40005 0)
			(size 0 0)
			(layers "F.Cu" "F.Mask" "F.Paste")
			(net "GND")
		)
	)
	(footprint ""
		(layer "F.Cu")
		(at 322.65366 -233.414824)
		(property "Reference" "R5646"
			(at 0 0 0)
			(layer "F.SilkS")
			(hide yes)
			(effects
				(font
					(size 1.27 1.27)
				)
			)
		)
		(property "Value" ""
			(at 0 0 0)
			(layer "F.Fab")
			(effects
				(font
					(size 1.27 1.27)
				)
			)
		)
		(duplicate_pad_numbers_are_jumpers no)
		(fp_line
			(start -0.7874 -0.4064)
			(end 0.7874 -0.4064)
			(stroke
				(width 0.1524)
				(type default)
			)
			(layer "F.SilkS")
		)
		(fp_line
			(start -0.7874 0.4064)
			(end -0.7874 -0.4064)
			(stroke
				(width 0.1524)
				(type default)
			)
			(layer "F.SilkS")
		)
		(fp_line
			(start 0.7874 -0.4064)
			(end 0.7874 0.4064)
			(stroke
				(width 0.1524)
				(type default)
			)
			(layer "F.SilkS")
		)
		(fp_line
			(start 0.7874 0.4064)
			(end -0.7874 0.4064)
			(stroke
				(width 0.1524)
				(type default)
			)
			(layer "F.SilkS")
		)
		(fp_line
			(start -0.67945 -0.305054)
			(end -0.12065 -0.305054)
			(stroke
				(width 0.1)
				(type default)
			)
			(layer "F.Fab")
		)
		(fp_line
			(start -0.67945 0.3048)
			(end -0.67945 -0.305054)
			(stroke
				(width 0.1)
				(type default)
			)
			(layer "F.Fab")
		)
		(fp_line
			(start -0.12065 -0.305054)
			(end -0.12065 -0.2794)
			(stroke
				(width 0.1)
				(type default)
			)
			(layer "F.Fab")
		)
		(fp_line
			(start -0.12065 -0.2794)
			(end 0.12065 -0.2794)
			(stroke
				(width 0.1)
				(type default)
			)
			(layer "F.Fab")
		)
		(fp_line
			(start -0.12065 0.2794)
			(end -0.12065 0.3048)
			(stroke
				(width 0.1)
				(type default)
			)
			(layer "F.Fab")
		)
		(fp_line
			(start -0.12065 0.3048)
			(end -0.67945 0.3048)
			(stroke
				(width 0.1)
				(type default)
			)
			(layer "F.Fab")
		)
		(fp_line
			(start 0.120396 0.2794)
			(end -0.12065 0.2794)
			(stroke
				(width 0.1)
				(type default)
			)
			(layer "F.Fab")
		)
		(fp_line
			(start 0.120396 0.3048)
			(end 0.120396 0.2794)
			(stroke
				(width 0.1)
				(type default)
			)
			(layer "F.Fab")
		)
		(fp_line
			(start 0.12065 -0.3048)
			(end 0.67945 -0.3048)
			(stroke
				(width 0.1)
				(type default)
			)
			(layer "F.Fab")
		)
		(fp_line
			(start 0.12065 -0.2794)
			(end 0.12065 -0.3048)
			(stroke
				(width 0.1)
				(type default)
			)
			(layer "F.Fab")
		)
		(fp_line
			(start 0.67945 -0.3048)
			(end 0.67945 0.3048)
			(stroke
				(width 0.1)
				(type default)
			)
			(layer "F.Fab")
		)
		(fp_line
			(start 0.67945 0.3048)
			(end 0.120396 0.3048)
			(stroke
				(width 0.1)
				(type default)
			)
			(layer "F.Fab")
		)
		(pad "1" smd circle
			(at -0.40005 0)
			(size 0 0)
			(layers "F.Cu" "F.Mask" "F.Paste")
			(net "SMB_MB_R_SCL")
		)
		(pad "2" smd circle
			(at 0.40005 0)
			(size 0 0)
			(layers "F.Cu" "F.Mask" "F.Paste")
			(net "SMB_MB_BMC_ISO_FPGA_SCL")
		)
	)
	(footprint ""
		(layer "F.Cu")
		(at 112.311942 -107.848654 180)
		(property "Reference" "R906"
			(at 0 0 180)
			(layer "F.SilkS")
			(hide yes)
			(effects
				(font
					(size 1.27 1.27)
				)
			)
		)
		(property "Value" ""
			(at 0 0 180)
			(layer "F.Fab")
			(effects
				(font
					(size 1.27 1.27)
				)
			)
		)
		(duplicate_pad_numbers_are_jumpers no)
		(fp_line
			(start 0.7874 0.4064)
			(end -0.7874 0.4064)
			(stroke
				(width 0.1524)
				(type default)
			)
			(layer "F.SilkS")
		)
		(fp_line
			(start 0.7874 -0.4064)
			(end 0.7874 0.4064)
			(stroke
				(width 0.1524)
				(type default)
			)
			(layer "F.SilkS")
		)
		(fp_line
			(start -0.7874 0.4064)
			(end -0.7874 -0.4064)
			(stroke
				(width 0.1524)
				(type default)
			)
			(layer "F.SilkS")
		)
		(fp_line
			(start -0.7874 -0.4064)
			(end 0.7874 -0.4064)
			(stroke
				(width 0.1524)
				(type default)
			)
			(layer "F.SilkS")
		)
		(fp_line
			(start 0.67945 0.3048)
			(end 0.120396 0.3048)
			(stroke
				(width 0.1)
				(type default)
			)
			(layer "F.Fab")
		)
		(fp_line
			(start 0.67945 -0.3048)
			(end 0.67945 0.3048)
			(stroke
				(width 0.1)
				(type default)
			)
			(layer "F.Fab")
		)
		(fp_line
			(start 0.12065 -0.2794)
			(end 0.12065 -0.3048)
			(stroke
				(width 0.1)
				(type default)
			)
			(layer "F.Fab")
		)
		(fp_line
			(start 0.12065 -0.3048)
			(end 0.67945 -0.3048)
			(stroke
				(width 0.1)
				(type default)
			)
			(layer "F.Fab")
		)
		(fp_line
			(start 0.120396 0.3048)
			(end 0.120396 0.2794)
			(stroke
				(width 0.1)
				(type default)
			)
			(layer "F.Fab")
		)
		(fp_line
			(start 0.120396 0.2794)
			(end -0.12065 0.2794)
			(stroke
				(width 0.1)
				(type default)
			)
			(layer "F.Fab")
		)
		(fp_line
			(start -0.12065 0.3048)
			(end -0.67945 0.3048)
			(stroke
				(width 0.1)
				(type default)
			)
			(layer "F.Fab")
		)
		(fp_line
			(start -0.12065 0.2794)
			(end -0.12065 0.3048)
			(stroke
				(width 0.1)
				(type default)
			)
			(layer "F.Fab")
		)
		(fp_line
			(start -0.12065 -0.2794)
			(end 0.12065 -0.2794)
			(stroke
				(width 0.1)
				(type default)
			)
			(layer "F.Fab")
		)
		(fp_line
			(start -0.12065 -0.305054)
			(end -0.12065 -0.2794)
			(stroke
				(width 0.1)
				(type default)
			)
			(layer "F.Fab")
		)
		(fp_line
			(start -0.67945 0.3048)
			(end -0.67945 -0.305054)
			(stroke
				(width 0.1)
				(type default)
			)
			(layer "F.Fab")
		)
		(fp_line
			(start -0.67945 -0.305054)
			(end -0.12065 -0.305054)
			(stroke
				(width 0.1)
				(type default)
			)
			(layer "F.Fab")
		)
		(pad "1" smd circle
			(at -0.40005 0 180)
			(size 0 0)
			(layers "F.Cu" "F.Mask" "F.Paste")
			(net "HP_NIC1_EN")
		)
		(pad "2" smd circle
			(at 0.40005 0 180)
			(size 0 0)
			(layers "F.Cu" "F.Mask" "F.Paste")
			(net "P12V_NIC1_CO_EN")
		)
	)
	(footprint ""
		(layer "F.Cu")
		(at 394.734542 -30.94609 180)
		(property "Reference" "C710"
			(at 0 0 180)
			(layer "F.SilkS")
			(hide yes)
			(effects
				(font
					(size 1.27 1.27)
				)
			)
		)
		(property "Value" ""
			(at 0 0 180)
			(layer "F.Fab")
			(effects
				(font
					(size 1.27 1.27)
				)
			)
		)
		(duplicate_pad_numbers_are_jumpers no)
		(fp_line
			(start 0.299974 0.150114)
			(end -0.299974 0.150114)
			(stroke
				(width 0.1)
				(type default)
			)
			(layer "F.Fab")
		)
		(fp_line
			(start 0.299974 -0.150114)
			(end 0.299974 0.150114)
			(stroke
				(width 0.1)
				(type default)
			)
			(layer "F.Fab")
		)
		(fp_line
			(start -0.299974 0.150114)
			(end -0.299974 -0.150114)
			(stroke
				(width 0.1)
				(type default)
			)
			(layer "F.Fab")
		)
		(fp_line
			(start -0.299974 -0.150114)
			(end 0.299974 -0.150114)
			(stroke
				(width 0.1)
				(type default)
			)
			(layer "F.Fab")
		)
		(pad "1" smd rect
			(at -0.2667 0 180)
			(size 0.3048 0.381)
			(layers "F.Cu" "F.Mask" "F.Paste")
			(net "P5E_PEX3_STN2_TX_DP<41>")
		)
		(pad "2" smd rect
			(at 0.2667 0 180)
			(size 0.3048 0.381)
			(layers "F.Cu" "F.Mask" "F.Paste")
			(net "P5E_PEX3_STN2_TX_C_DP<41>")
		)
	)
	(footprint ""
		(layer "F.Cu")
		(at 345.76131 -262.703564 180)
		(property "Reference" "PR131"
			(at 0 0 180)
			(layer "F.SilkS")
			(hide yes)
			(effects
				(font
					(size 1.27 1.27)
				)
			)
		)
		(property "Value" ""
			(at 0 0 180)
			(layer "F.Fab")
			(effects
				(font
					(size 1.27 1.27)
				)
			)
		)
		(duplicate_pad_numbers_are_jumpers no)
		(fp_line
			(start 0.7874 0.4064)
			(end -0.7874 0.4064)
			(stroke
				(width 0.1524)
				(type default)
			)
			(layer "F.SilkS")
		)
		(fp_line
			(start 0.7874 -0.4064)
			(end 0.7874 0.4064)
			(stroke
				(width 0.1524)
				(type default)
			)
			(layer "F.SilkS")
		)
		(fp_line
			(start -0.7874 0.4064)
			(end -0.7874 -0.4064)
			(stroke
				(width 0.1524)
				(type default)
			)
			(layer "F.SilkS")
		)
		(fp_line
			(start -0.7874 -0.4064)
			(end 0.7874 -0.4064)
			(stroke
				(width 0.1524)
				(type default)
			)
			(layer "F.SilkS")
		)
		(fp_line
			(start 0.67945 0.3048)
			(end 0.120396 0.3048)
			(stroke
				(width 0.1)
				(type default)
			)
			(layer "F.Fab")
		)
		(fp_line
			(start 0.67945 -0.3048)
			(end 0.67945 0.3048)
			(stroke
				(width 0.1)
				(type default)
			)
			(layer "F.Fab")
		)
		(fp_line
			(start 0.12065 -0.2794)
			(end 0.12065 -0.3048)
			(stroke
				(width 0.1)
				(type default)
			)
			(layer "F.Fab")
		)
		(fp_line
			(start 0.12065 -0.3048)
			(end 0.67945 -0.3048)
			(stroke
				(width 0.1)
				(type default)
			)
			(layer "F.Fab")
		)
		(fp_line
			(start 0.120396 0.3048)
			(end 0.120396 0.2794)
			(stroke
				(width 0.1)
				(type default)
			)
			(layer "F.Fab")
		)
		(fp_line
			(start 0.120396 0.2794)
			(end -0.12065 0.2794)
			(stroke
				(width 0.1)
				(type default)
			)
			(layer "F.Fab")
		)
		(fp_line
			(start -0.12065 0.3048)
			(end -0.67945 0.3048)
			(stroke
				(width 0.1)
				(type default)
			)
			(layer "F.Fab")
		)
		(fp_line
			(start -0.12065 0.2794)
			(end -0.12065 0.3048)
			(stroke
				(width 0.1)
				(type default)
			)
			(layer "F.Fab")
		)
		(fp_line
			(start -0.12065 -0.2794)
			(end 0.12065 -0.2794)
			(stroke
				(width 0.1)
				(type default)
			)
			(layer "F.Fab")
		)
		(fp_line
			(start -0.12065 -0.305054)
			(end -0.12065 -0.2794)
			(stroke
				(width 0.1)
				(type default)
			)
			(layer "F.Fab")
		)
		(fp_line
			(start -0.67945 0.3048)
			(end -0.67945 -0.305054)
			(stroke
				(width 0.1)
				(type default)
			)
			(layer "F.Fab")
		)
		(fp_line
			(start -0.67945 -0.305054)
			(end -0.12065 -0.305054)
			(stroke
				(width 0.1)
				(type default)
			)
			(layer "F.Fab")
		)
		(pad "1" smd circle
			(at -0.40005 0 180)
			(size 0 0)
			(layers "F.Cu" "F.Mask" "F.Paste")
			(net "P0V8_PEX2_VR_CONFIG")
		)
		(pad "2" smd circle
			(at 0.40005 0 180)
			(size 0 0)
			(layers "F.Cu" "F.Mask" "F.Paste")
			(net "P3V3_AUX")
		)
	)
	(footprint ""
		(layer "F.Cu")
		(at 210.542886 -231.150922 90)
		(property "Reference" "R1545"
			(at 0 0 90)
			(layer "F.SilkS")
			(hide yes)
			(effects
				(font
					(size 1.27 1.27)
				)
			)
		)
		(property "Value" ""
			(at 0 0 90)
			(layer "F.Fab")
			(effects
				(font
					(size 1.27 1.27)
				)
			)
		)
		(duplicate_pad_numbers_are_jumpers no)
		(fp_line
			(start 0.7874 -0.4064)
			(end 0.7874 0.4064)
			(stroke
				(width 0.1524)
				(type default)
			)
			(layer "F.SilkS")
		)
		(fp_line
			(start -0.7874 -0.4064)
			(end 0.7874 -0.4064)
			(stroke
				(width 0.1524)
				(type default)
			)
			(layer "F.SilkS")
		)
		(fp_line
			(start 0.7874 0.4064)
			(end -0.7874 0.4064)
			(stroke
				(width 0.1524)
				(type default)
			)
			(layer "F.SilkS")
		)
		(fp_line
			(start -0.7874 0.4064)
			(end -0.7874 -0.4064)
			(stroke
				(width 0.1524)
				(type default)
			)
			(layer "F.SilkS")
		)
		(fp_line
			(start -0.12065 -0.305054)
			(end -0.12065 -0.2794)
			(stroke
				(width 0.1)
				(type default)
			)
			(layer "F.Fab")
		)
		(fp_line
			(start -0.67945 -0.305054)
			(end -0.12065 -0.305054)
			(stroke
				(width 0.1)
				(type default)
			)
			(layer "F.Fab")
		)
		(fp_line
			(start 0.67945 -0.3048)
			(end 0.67945 0.3048)
			(stroke
				(width 0.1)
				(type default)
			)
			(layer "F.Fab")
		)
		(fp_line
			(start 0.12065 -0.3048)
			(end 0.67945 -0.3048)
			(stroke
				(width 0.1)
				(type default)
			)
			(layer "F.Fab")
		)
		(fp_line
			(start 0.12065 -0.2794)
			(end 0.12065 -0.3048)
			(stroke
				(width 0.1)
				(type default)
			)
			(layer "F.Fab")
		)
		(fp_line
			(start -0.12065 -0.2794)
			(end 0.12065 -0.2794)
			(stroke
				(width 0.1)
				(type default)
			)
			(layer "F.Fab")
		)
		(fp_line
			(start 0.120396 0.2794)
			(end -0.12065 0.2794)
			(stroke
				(width 0.1)
				(type default)
			)
			(layer "F.Fab")
		)
		(fp_line
			(start -0.12065 0.2794)
			(end -0.12065 0.3048)
			(stroke
				(width 0.1)
				(type default)
			)
			(layer "F.Fab")
		)
		(fp_line
			(start 0.67945 0.3048)
			(end 0.120396 0.3048)
			(stroke
				(width 0.1)
				(type default)
			)
			(layer "F.Fab")
		)
		(fp_line
			(start 0.120396 0.3048)
			(end 0.120396 0.2794)
			(stroke
				(width 0.1)
				(type default)
			)
			(layer "F.Fab")
		)
		(fp_line
			(start -0.12065 0.3048)
			(end -0.67945 0.3048)
			(stroke
				(width 0.1)
				(type default)
			)
			(layer "F.Fab")
		)
		(fp_line
			(start -0.67945 0.3048)
			(end -0.67945 -0.305054)
			(stroke
				(width 0.1)
				(type default)
			)
			(layer "F.Fab")
		)
		(pad "1" smd circle
			(at -0.40005 0 90)
			(size 0 0)
			(layers "F.Cu" "F.Mask" "F.Paste")
			(net "SMB_PEX_LS_R_SDA")
		)
		(pad "2" smd circle
			(at 0.40005 0 90)
			(size 0 0)
			(layers "F.Cu" "F.Mask" "F.Paste")
			(net "SMB_PEX1_SDA")
		)
	)
	(footprint ""
		(layer "F.Cu")
		(at 426.434504 -87.599012)
		(property "Reference" "U45"
			(at -0.933704 -1.706118 0)
			(unlocked yes)
			(layer "F.SilkS")
			(effects
				(font
					(size 0.7874 0.5842)
					(thickness 0.1524)
				)
				(justify left)
			)
		)
		(property "Value" ""
			(at 0 0 0)
			(layer "F.Fab")
			(effects
				(font
					(size 1.27 1.27)
				)
			)
		)
		(duplicate_pad_numbers_are_jumpers no)
		(fp_line
			(start -1.684274 -1.074928)
			(end -0.381 -1.074928)
			(stroke
				(width 0.1524)
				(type default)
			)
			(layer "F.SilkS")
		)
		(fp_line
			(start -1.684274 1.074928)
			(end -1.684274 -1.074928)
			(stroke
				(width 0.1524)
				(type default)
			)
			(layer "F.SilkS")
		)
		(fp_line
			(start -0.381 -1.074928)
			(end 0 -0.625094)
			(stroke
				(width 0.1524)
				(type default)
			)
			(layer "F.SilkS")
		)
		(fp_line
			(start 0 -0.625094)
			(end 0.381 -1.074928)
			(stroke
				(width 0.1524)
				(type default)
			)
			(layer "F.SilkS")
		)
		(fp_line
			(start 0.381 -1.074928)
			(end 1.684274 -1.074928)
			(stroke
				(width 0.1524)
				(type default)
			)
			(layer "F.SilkS")
		)
		(fp_line
			(start 1.684274 -1.074928)
			(end 1.684274 1.074928)
			(stroke
				(width 0.1524)
				(type default)
			)
			(layer "F.SilkS")
		)
		(fp_line
			(start 1.684274 1.074928)
			(end -1.684274 1.074928)
			(stroke
				(width 0.1524)
				(type default)
			)
			(layer "F.SilkS")
		)
		(fp_poly
			(pts
				(xy -2.637282 -0.903986) (xy -2.637282 -0.395986) (xy -1.875282 -0.649986)
			)
			(stroke
				(width 0)
				(type default)
			)
			(fill yes)
			(layer "F.SilkS")
		)
		(fp_line
			(start -0.700024 -1.074928)
			(end -0.700024 1.074928)
			(stroke
				(width 0.1)
				(type default)
			)
			(layer "F.Fab")
		)
		(fp_line
			(start -0.700024 1.074928)
			(end 0.700024 1.074928)
			(stroke
				(width 0.1)
				(type default)
			)
			(layer "F.Fab")
		)
		(fp_line
			(start 0.700024 -1.074928)
			(end -0.700024 -1.074928)
			(stroke
				(width 0.1)
				(type default)
			)
			(layer "F.Fab")
		)
		(fp_line
			(start 0.700024 1.074928)
			(end 0.700024 -1.074928)
			(stroke
				(width 0.1)
				(type default)
			)
			(layer "F.Fab")
		)
		(fp_poly
			(pts
				(xy -2.637282 -0.903986) (xy -2.637282 -0.395986) (xy -1.875282 -0.649986)
			)
			(stroke
				(width 0)
				(type default)
			)
			(fill yes)
			(layer "F.Fab")
		)
		(pad "1" smd rect
			(at -1.100074 -0.649986 270)
			(size 0.4064 0.9144)
			(layers "F.Cu" "F.Mask" "F.Paste")
			(net "Net_8449")
		)
		(pad "2" smd rect
			(at -1.100074 0 270)
			(size 0.4064 0.9144)
			(layers "F.Cu" "F.Mask" "F.Paste")
			(net "RST_HP_NIC7_N")
		)
		(pad "3" smd rect
			(at -1.100074 0.649986 270)
			(size 0.4064 0.9144)
			(layers "F.Cu" "F.Mask" "F.Paste")
			(net "GND")
		)
		(pad "4" smd rect
			(at 1.100074 0.649986 270)
			(size 0.4064 0.9144)
			(layers "F.Cu" "F.Mask" "F.Paste")
			(net "RST_HP_NIC7_BUF_N")
		)
		(pad "5" smd rect
			(at 1.100074 -0.649986 270)
			(size 0.4064 0.9144)
			(layers "F.Cu" "F.Mask" "F.Paste")
			(net "P3V3_AUX")
		)
	)
)
